# Stackup_F0T_Fan_BP_6L_1p6mm_IT-170GT_RTF_Rev0p1_20211021.xls — Information (pcb-stackup)
| Stackup Information : |  |  |  |
| Stackup Type |  |  | Single Material |
| Project Name |  |  | F0T |
| Board Class |  |  | Fan_BP |
| Number of Layers |  |  | 6 |
| PCB Material |  |  | IT-170GT |
| Copper Foil |  |  | RTF (Roughness < 4um) |
| PCB Thickness (mm) |  |  | 1.6 |
| PCB Thickness (mil) |  |  | 63 |
| Aspect Ratio |  |  | 6.43 |
| Last Update |  |  | 44490 |
| Revision |  |  | 0.1 |
| Creator |  |  | Allen |
| Loss Requirement Table : |  |  |  |
| SDD21 @ Freq(GHz) |  |  |  |
| Requirement (db/inch) | Layer |  |  |
|  | Loss |  |  |
| Stackup History : |  |  |  |
| Date (yyyy/mm/dd) | Revision | Notes |  |
| 44490 | 0.1 | First release |  |
